(kicad_pcb
	(version 20260206)
	(generator "pcbnew")
	(generator_version "10.0")
	(general
		(thickness 1.6)
		(legacy_teardrops no)
	)
	(paper "A4")
	(title_block
		(title "03242023_DA0F0TMBIJ0_F0T_Motherboard_J_brd_V01_OCP.brd")
		(comment 1 "Grand Teton / footprints 1516-1521 of 6105")
	)
	(layers
		(0 "F.Cu" signal "TOP")
		(4 "In1.Cu" signal "GND")
		(6 "In2.Cu" signal "IN1")
		(8 "In3.Cu" signal "GND1")
		(10 "In4.Cu" signal "IN2")
		(12 "In5.Cu" signal "GND2")
		(14 "In6.Cu" signal "IN3")
		(16 "In7.Cu" signal "GND3")
		(18 "In8.Cu" signal "VCC")
		(20 "In9.Cu" signal "VCC1")
		(22 "In10.Cu" signal "GND4")
		(24 "In11.Cu" signal "IN4")
		(26 "In12.Cu" signal "GND5")
		(28 "In13.Cu" signal "IN5")
		(30 "In14.Cu" signal "GND6")
		(32 "In15.Cu" signal "IN6")
		(34 "In16.Cu" signal "GND7")
		(2 "B.Cu" signal "BOTTOM")
		(9 "F.Adhes" user "F.Adhesive")
		(11 "B.Adhes" user "B.Adhesive")
		(13 "F.Paste" user "Package Geometry/Pastemask Top")
		(15 "B.Paste" user "Package Geometry/Pastemask Bottom")
		(5 "F.SilkS" user "Ref Des/Silkscreen Top")
		(7 "B.SilkS" user "Ref Des/Silkscreen Bottom")
		(1 "F.Mask" user "Board Geometry/Soldermask Top")
		(3 "B.Mask" user "Board Geometry/Soldermask Bottom")
		(17 "Dwgs.User" user "User.Drawings")
		(19 "Cmts.User" user "User.Comments")
		(21 "Eco1.User" user "User.Eco1")
		(23 "Eco2.User" user "User.Eco2")
		(25 "Edge.Cuts" user "Board Geometry/Outline")
		(27 "Margin" user)
		(31 "F.CrtYd" user "Package Geometry/Place Bound Top")
		(29 "B.CrtYd" user "Package Geometry/Place Bound Bottom")
		(35 "F.Fab" user "Ref Des/Assembly Top")
		(33 "B.Fab" user "Ref Des/Assembly Bottom")
	)
	(footprint ""
		(layer "F.Cu")
		(at 293.579042 -51.091338 90)
		(property "Reference" "Q127"
			(at 0.542036 -6.504432 0)
			(unlocked yes)
			(layer "F.SilkS")
			(effects
				(font
					(size 0.7874 0.5842)
					(thickness 0.1524)
				)
				(justify left)
			)
		)
		(property "Value" ""
			(at 0 0 90)
			(layer "F.Fab")
			(effects
				(font
					(size 1.27 1.27)
				)
			)
		)
		(duplicate_pad_numbers_are_jumpers no)
		(fp_line
			(start 1.332738 -1.100074)
			(end 1.332738 1.100074)
			(stroke
				(width 0.1524)
				(type default)
			)
			(layer "F.SilkS")
		)
		(fp_line
			(start 0.4826 -1.100074)
			(end 1.332738 -1.100074)
			(stroke
				(width 0.1524)
				(type default)
			)
			(layer "F.SilkS")
		)
		(fp_line
			(start -0.4826 -1.100074)
			(end 0 -0.541274)
			(stroke
				(width 0.1524)
				(type default)
			)
			(layer "F.SilkS")
		)
		(fp_line
			(start -1.332738 -1.100074)
			(end -0.4826 -1.100074)
			(stroke
				(width 0.1524)
				(type default)
			)
			(layer "F.SilkS")
		)
		(fp_line
			(start 0 -0.541274)
			(end 0.4826 -1.100074)
			(stroke
				(width 0.1524)
				(type default)
			)
			(layer "F.SilkS")
		)
		(fp_line
			(start 1.332738 1.100074)
			(end -1.332738 1.100074)
			(stroke
				(width 0.1524)
				(type default)
			)
			(layer "F.SilkS")
		)
		(fp_line
			(start -1.332738 1.100074)
			(end -1.332738 -1.100074)
			(stroke
				(width 0.1524)
				(type default)
			)
			(layer "F.SilkS")
		)
		(fp_poly
			(pts
				(xy -2.43332 -1.270254) (xy -1.731264 -0.919226) (xy -2.43332 -0.568198)
			)
			(stroke
				(width 0)
				(type default)
			)
			(fill yes)
			(layer "F.SilkS")
		)
		(fp_line
			(start 0.674878 -1.100074)
			(end 0.674878 1.100074)
			(stroke
				(width 0.1)
				(type default)
			)
			(layer "F.Fab")
		)
		(fp_line
			(start -0.674878 -1.100074)
			(end 0.674878 -1.100074)
			(stroke
				(width 0.1)
				(type default)
			)
			(layer "F.Fab")
		)
		(fp_line
			(start 0.674878 1.100074)
			(end -0.674878 1.100074)
			(stroke
				(width 0.1)
				(type default)
			)
			(layer "F.Fab")
		)
		(fp_line
			(start -0.674878 1.100074)
			(end -0.674878 -1.100074)
			(stroke
				(width 0.1)
				(type default)
			)
			(layer "F.Fab")
		)
		(fp_poly
			(pts
				(xy -2.2352 -0.298958) (xy -2.2352 -1.001014) (xy -1.533144 -0.649986)
			)
			(stroke
				(width 0)
				(type default)
			)
			(fill yes)
			(layer "F.Fab")
		)
		(pad "1" smd rect
			(at -0.94996 -0.649986 180)
			(size 0.4318 0.508)
			(layers "F.Cu" "F.Mask" "F.Paste")
			(net "GND")
		)
		(pad "2" smd rect
			(at -0.94996 0 180)
			(size 0.4318 0.508)
			(layers "F.Cu" "F.Mask" "F.Paste")
			(net "P12V_E1S_EN_0_R")
		)
		(pad "3" smd rect
			(at -0.94996 0.649986 180)
			(size 0.4318 0.508)
			(layers "F.Cu" "F.Mask" "F.Paste")
			(net "P12V_E1S_UV_0_R")
		)
		(pad "4" smd rect
			(at 0.94996 0.649986 180)
			(size 0.4318 0.508)
			(layers "F.Cu" "F.Mask" "F.Paste")
			(net "GND")
		)
		(pad "5" smd rect
			(at 0.94996 0 180)
			(size 0.4318 0.508)
			(layers "F.Cu" "F.Mask" "F.Paste")
			(net "P12V_E1S_0_EN_G")
		)
		(pad "6" smd rect
			(at 0.94996 -0.649986 180)
			(size 0.4318 0.508)
			(layers "F.Cu" "F.Mask" "F.Paste")
			(net "P12V_E1S_0_EN_G")
		)
	)
	(footprint ""
		(layer "F.Cu")
		(at 307.361336 -59.037728 90)
		(property "Reference" "U142"
			(at -0.091186 3.191764 0)
			(unlocked yes)
			(layer "F.SilkS")
			(effects
				(font
					(size 0.7874 0.5842)
					(thickness 0.1524)
				)
			)
		)
		(property "Value" ""
			(at 0 0 90)
			(layer "F.Fab")
			(effects
				(font
					(size 1.27 1.27)
				)
			)
		)
		(duplicate_pad_numbers_are_jumpers no)
		(fp_line
			(start 1.7272 -1.1176)
			(end 0.254 -1.1176)
			(stroke
				(width 0.1524)
				(type default)
			)
			(layer "F.SilkS")
		)
		(fp_line
			(start 1.7272 -1.1176)
			(end 1.7272 1.1176)
			(stroke
				(width 0.1524)
				(type default)
			)
			(layer "F.SilkS")
		)
		(fp_line
			(start 0.254 -1.1176)
			(end 0 -0.7366)
			(stroke
				(width 0.1524)
				(type default)
			)
			(layer "F.SilkS")
		)
		(fp_line
			(start -0.254 -1.1176)
			(end -1.7272 -1.1176)
			(stroke
				(width 0.1524)
				(type default)
			)
			(layer "F.SilkS")
		)
		(fp_line
			(start 0 -0.7366)
			(end -0.254 -1.1176)
			(stroke
				(width 0.1524)
				(type default)
			)
			(layer "F.SilkS")
		)
		(fp_line
			(start 1.7272 1.1176)
			(end -1.7272 1.1176)
			(stroke
				(width 0.1524)
				(type default)
			)
			(layer "F.SilkS")
		)
		(fp_line
			(start -1.7272 1.1176)
			(end -1.7272 -1.1176)
			(stroke
				(width 0.1524)
				(type default)
			)
			(layer "F.SilkS")
		)
		(fp_poly
			(pts
				(xy -1.31953 -1.375156) (xy -1.70053 -2.137156) (xy -0.93853 -2.137156)
			)
			(stroke
				(width 0)
				(type default)
			)
			(fill yes)
			(layer "F.SilkS")
		)
		(fp_line
			(start 1.5748 -1.1176)
			(end -1.5748 -1.1176)
			(stroke
				(width 0.1)
				(type default)
			)
			(layer "F.Fab")
		)
		(fp_line
			(start -1.5748 -1.1176)
			(end -1.5748 1.1176)
			(stroke
				(width 0.1)
				(type default)
			)
			(layer "F.Fab")
		)
		(fp_line
			(start 1.5748 1.1176)
			(end 1.5748 -1.1176)
			(stroke
				(width 0.1)
				(type default)
			)
			(layer "F.Fab")
		)
		(fp_line
			(start -1.5748 1.1176)
			(end 1.5748 1.1176)
			(stroke
				(width 0.1)
				(type default)
			)
			(layer "F.Fab")
		)
		(fp_poly
			(pts
				(xy -1.9558 -0.649986) (xy -2.7178 -0.268986) (xy -2.7178 -1.030986)
			)
			(stroke
				(width 0)
				(type default)
			)
			(fill yes)
			(layer "F.Fab")
		)
		(pad "1" smd rect
			(at -0.999998 -0.649986)
			(size 0.3556 1.1176)
			(layers "F.Cu" "F.Mask" "F.Paste")
			(net "PECI_BMC_B1")
		)
		(pad "2" smd rect
			(at -0.999998 0)
			(size 0.3556 1.1176)
			(layers "F.Cu" "F.Mask" "F.Paste")
			(net "GND")
		)
		(pad "3" smd rect
			(at -0.999998 0.649986)
			(size 0.3556 1.1176)
			(layers "F.Cu" "F.Mask" "F.Paste")
			(net "PECI_PCH_B1")
		)
		(pad "4" smd rect
			(at 0.999998 0.649986)
			(size 0.3556 1.1176)
			(layers "F.Cu" "F.Mask" "F.Paste")
			(net "PECI_CPU_GTL")
		)
		(pad "5" smd rect
			(at 0.999998 0)
			(size 0.3556 1.1176)
			(layers "F.Cu" "F.Mask" "F.Paste")
			(net "P3V3_AUX")
		)
		(pad "6" smd rect
			(at 0.999998 -0.649986)
			(size 0.3556 1.1176)
			(layers "F.Cu" "F.Mask" "F.Paste")
			(net "PECI_MUX_SEL_R")
		)
	)
	(footprint ""
		(layer "F.Cu")
		(at 376.658632 -71.489824)
		(property "Reference" "PC1236"
			(at 0 0 0)
			(layer "F.SilkS")
			(hide yes)
			(effects
				(font
					(size 1.27 1.27)
				)
			)
		)
		(property "Value" ""
			(at 0 0 0)
			(layer "F.Fab")
			(effects
				(font
					(size 1.27 1.27)
				)
			)
		)
		(duplicate_pad_numbers_are_jumpers no)
		(fp_line
			(start -0.7874 -0.4064)
			(end 0.7874 -0.4064)
			(stroke
				(width 0.1524)
				(type default)
			)
			(layer "F.SilkS")
		)
		(fp_line
			(start -0.7874 0.4064)
			(end -0.7874 -0.4064)
			(stroke
				(width 0.1524)
				(type default)
			)
			(layer "F.SilkS")
		)
		(fp_line
			(start 0.7874 -0.4064)
			(end 0.7874 0.4064)
			(stroke
				(width 0.1524)
				(type default)
			)
			(layer "F.SilkS")
		)
		(fp_line
			(start 0.7874 0.4064)
			(end -0.7874 0.4064)
			(stroke
				(width 0.1524)
				(type default)
			)
			(layer "F.SilkS")
		)
		(fp_line
			(start -0.67945 -0.305054)
			(end -0.12065 -0.305054)
			(stroke
				(width 0.1)
				(type default)
			)
			(layer "F.Fab")
		)
		(fp_line
			(start -0.67945 0.3048)
			(end -0.67945 -0.305054)
			(stroke
				(width 0.1)
				(type default)
			)
			(layer "F.Fab")
		)
		(fp_line
			(start -0.12065 -0.305054)
			(end -0.12065 -0.2794)
			(stroke
				(width 0.1)
				(type default)
			)
			(layer "F.Fab")
		)
		(fp_line
			(start -0.12065 -0.2794)
			(end 0.12065 -0.2794)
			(stroke
				(width 0.1)
				(type default)
			)
			(layer "F.Fab")
		)
		(fp_line
			(start -0.12065 0.2794)
			(end -0.12065 0.3048)
			(stroke
				(width 0.1)
				(type default)
			)
			(layer "F.Fab")
		)
		(fp_line
			(start -0.12065 0.3048)
			(end -0.67945 0.3048)
			(stroke
				(width 0.1)
				(type default)
			)
			(layer "F.Fab")
		)
		(fp_line
			(start 0.120396 0.2794)
			(end -0.12065 0.2794)
			(stroke
				(width 0.1)
				(type default)
			)
			(layer "F.Fab")
		)
		(fp_line
			(start 0.120396 0.3048)
			(end 0.120396 0.2794)
			(stroke
				(width 0.1)
				(type default)
			)
			(layer "F.Fab")
		)
		(fp_line
			(start 0.12065 -0.3048)
			(end 0.67945 -0.3048)
			(stroke
				(width 0.1)
				(type default)
			)
			(layer "F.Fab")
		)
		(fp_line
			(start 0.12065 -0.2794)
			(end 0.12065 -0.3048)
			(stroke
				(width 0.1)
				(type default)
			)
			(layer "F.Fab")
		)
		(fp_line
			(start 0.67945 -0.3048)
			(end 0.67945 0.3048)
			(stroke
				(width 0.1)
				(type default)
			)
			(layer "F.Fab")
		)
		(fp_line
			(start 0.67945 0.3048)
			(end 0.120396 0.3048)
			(stroke
				(width 0.1)
				(type default)
			)
			(layer "F.Fab")
		)
		(pad "1" smd circle
			(at -0.40005 0)
			(size 0 0)
			(layers "F.Cu" "F.Mask" "F.Paste")
			(net "P1V8_PCH_AUX")
		)
		(pad "2" smd circle
			(at 0.40005 0)
			(size 0 0)
			(layers "F.Cu" "F.Mask" "F.Paste")
			(net "GND")
		)
	)
	(footprint ""
		(layer "F.Cu")
		(at 295.86682 -419.02761 -90)
		(property "Reference" "C2270"
			(at 0 0 270)
			(layer "F.SilkS")
			(hide yes)
			(effects
				(font
					(size 1.27 1.27)
				)
			)
		)
		(property "Value" ""
			(at 0 0 270)
			(layer "F.Fab")
			(effects
				(font
					(size 1.27 1.27)
				)
			)
		)
		(duplicate_pad_numbers_are_jumpers no)
		(fp_line
			(start -0.7874 0.4064)
			(end -0.7874 -0.4064)
			(stroke
				(width 0.1524)
				(type default)
			)
			(layer "F.SilkS")
		)
		(fp_line
			(start 0.7874 0.4064)
			(end -0.7874 0.4064)
			(stroke
				(width 0.1524)
				(type default)
			)
			(layer "F.SilkS")
		)
		(fp_line
			(start -0.7874 -0.4064)
			(end 0.7874 -0.4064)
			(stroke
				(width 0.1524)
				(type default)
			)
			(layer "F.SilkS")
		)
		(fp_line
			(start 0.7874 -0.4064)
			(end 0.7874 0.4064)
			(stroke
				(width 0.1524)
				(type default)
			)
			(layer "F.SilkS")
		)
		(fp_line
			(start -0.67945 0.3048)
			(end -0.67945 -0.305054)
			(stroke
				(width 0.1)
				(type default)
			)
			(layer "F.Fab")
		)
		(fp_line
			(start -0.12065 0.3048)
			(end -0.67945 0.3048)
			(stroke
				(width 0.1)
				(type default)
			)
			(layer "F.Fab")
		)
		(fp_line
			(start 0.120396 0.3048)
			(end 0.120396 0.2794)
			(stroke
				(width 0.1)
				(type default)
			)
			(layer "F.Fab")
		)
		(fp_line
			(start 0.67945 0.3048)
			(end 0.120396 0.3048)
			(stroke
				(width 0.1)
				(type default)
			)
			(layer "F.Fab")
		)
		(fp_line
			(start -0.12065 0.2794)
			(end -0.12065 0.3048)
			(stroke
				(width 0.1)
				(type default)
			)
			(layer "F.Fab")
		)
		(fp_line
			(start 0.120396 0.2794)
			(end -0.12065 0.2794)
			(stroke
				(width 0.1)
				(type default)
			)
			(layer "F.Fab")
		)
		(fp_line
			(start -0.12065 -0.2794)
			(end 0.12065 -0.2794)
			(stroke
				(width 0.1)
				(type default)
			)
			(layer "F.Fab")
		)
		(fp_line
			(start 0.12065 -0.2794)
			(end 0.12065 -0.3048)
			(stroke
				(width 0.1)
				(type default)
			)
			(layer "F.Fab")
		)
		(fp_line
			(start 0.12065 -0.3048)
			(end 0.67945 -0.3048)
			(stroke
				(width 0.1)
				(type default)
			)
			(layer "F.Fab")
		)
		(fp_line
			(start 0.67945 -0.3048)
			(end 0.67945 0.3048)
			(stroke
				(width 0.1)
				(type default)
			)
			(layer "F.Fab")
		)
		(fp_line
			(start -0.67945 -0.305054)
			(end -0.12065 -0.305054)
			(stroke
				(width 0.1)
				(type default)
			)
			(layer "F.Fab")
		)
		(fp_line
			(start -0.12065 -0.305054)
			(end -0.12065 -0.2794)
			(stroke
				(width 0.1)
				(type default)
			)
			(layer "F.Fab")
		)
		(pad "1" smd circle
			(at -0.40005 0 270)
			(size 0 0)
			(layers "F.Cu" "F.Mask" "F.Paste")
			(net "PRSNT_CABLE_GPU_A1_ISO_N")
		)
		(pad "2" smd circle
			(at 0.40005 0 270)
			(size 0 0)
			(layers "F.Cu" "F.Mask" "F.Paste")
			(net "GND")
		)
	)
	(footprint ""
		(layer "F.Cu")
		(at 184.58688 -418.06876 90)
		(property "Reference" "R4794"
			(at 0 0 90)
			(layer "F.SilkS")
			(hide yes)
			(effects
				(font
					(size 1.27 1.27)
				)
			)
		)
		(property "Value" ""
			(at 0 0 90)
			(layer "F.Fab")
			(effects
				(font
					(size 1.27 1.27)
				)
			)
		)
		(duplicate_pad_numbers_are_jumpers no)
		(fp_line
			(start 0.7874 -0.4064)
			(end 0.7874 0.4064)
			(stroke
				(width 0.1524)
				(type default)
			)
			(layer "F.SilkS")
		)
		(fp_line
			(start -0.7874 -0.4064)
			(end 0.7874 -0.4064)
			(stroke
				(width 0.1524)
				(type default)
			)
			(layer "F.SilkS")
		)
		(fp_line
			(start 0.7874 0.4064)
			(end -0.7874 0.4064)
			(stroke
				(width 0.1524)
				(type default)
			)
			(layer "F.SilkS")
		)
		(fp_line
			(start -0.7874 0.4064)
			(end -0.7874 -0.4064)
			(stroke
				(width 0.1524)
				(type default)
			)
			(layer "F.SilkS")
		)
		(fp_line
			(start -0.12065 -0.305054)
			(end -0.12065 -0.2794)
			(stroke
				(width 0.1)
				(type default)
			)
			(layer "F.Fab")
		)
		(fp_line
			(start -0.67945 -0.305054)
			(end -0.12065 -0.305054)
			(stroke
				(width 0.1)
				(type default)
			)
			(layer "F.Fab")
		)
		(fp_line
			(start 0.67945 -0.3048)
			(end 0.67945 0.3048)
			(stroke
				(width 0.1)
				(type default)
			)
			(layer "F.Fab")
		)
		(fp_line
			(start 0.12065 -0.3048)
			(end 0.67945 -0.3048)
			(stroke
				(width 0.1)
				(type default)
			)
			(layer "F.Fab")
		)
		(fp_line
			(start 0.12065 -0.2794)
			(end 0.12065 -0.3048)
			(stroke
				(width 0.1)
				(type default)
			)
			(layer "F.Fab")
		)
		(fp_line
			(start -0.12065 -0.2794)
			(end 0.12065 -0.2794)
			(stroke
				(width 0.1)
				(type default)
			)
			(layer "F.Fab")
		)
		(fp_line
			(start 0.120396 0.2794)
			(end -0.12065 0.2794)
			(stroke
				(width 0.1)
				(type default)
			)
			(layer "F.Fab")
		)
		(fp_line
			(start -0.12065 0.2794)
			(end -0.12065 0.3048)
			(stroke
				(width 0.1)
				(type default)
			)
			(layer "F.Fab")
		)
		(fp_line
			(start 0.67945 0.3048)
			(end 0.120396 0.3048)
			(stroke
				(width 0.1)
				(type default)
			)
			(layer "F.Fab")
		)
		(fp_line
			(start 0.120396 0.3048)
			(end 0.120396 0.2794)
			(stroke
				(width 0.1)
				(type default)
			)
			(layer "F.Fab")
		)
		(fp_line
			(start -0.12065 0.3048)
			(end -0.67945 0.3048)
			(stroke
				(width 0.1)
				(type default)
			)
			(layer "F.Fab")
		)
		(fp_line
			(start -0.67945 0.3048)
			(end -0.67945 -0.305054)
			(stroke
				(width 0.1)
				(type default)
			)
			(layer "F.Fab")
		)
		(pad "1" smd circle
			(at -0.40005 0 90)
			(size 0 0)
			(layers "F.Cu" "F.Mask" "F.Paste")
			(net "HSC_D_OC_R2")
		)
		(pad "2" smd circle
			(at 0.40005 0 90)
			(size 0 0)
			(layers "F.Cu" "F.Mask" "F.Paste")
			(net "A_HSC_LOW_GATE")
		)
	)
	(footprint ""
		(layer "F.Cu")
		(at 113.494312 -136.520682)
		(property "Reference" "R2268"
			(at 0 0 0)
			(layer "F.SilkS")
			(hide yes)
			(effects
				(font
					(size 1.27 1.27)
				)
			)
		)
		(property "Value" ""
			(at 0 0 0)
			(layer "F.Fab")
			(effects
				(font
					(size 1.27 1.27)
				)
			)
		)
		(duplicate_pad_numbers_are_jumpers no)
		(fp_line
			(start -0.7874 -0.4064)
			(end 0.7874 -0.4064)
			(stroke
				(width 0.1524)
				(type default)
			)
			(layer "F.SilkS")
		)
		(fp_line
			(start -0.7874 0.4064)
			(end -0.7874 -0.4064)
			(stroke
				(width 0.1524)
				(type default)
			)
			(layer "F.SilkS")
		)
		(fp_line
			(start 0.7874 -0.4064)
			(end 0.7874 0.4064)
			(stroke
				(width 0.1524)
				(type default)
			)
			(layer "F.SilkS")
		)
		(fp_line
			(start 0.7874 0.4064)
			(end -0.7874 0.4064)
			(stroke
				(width 0.1524)
				(type default)
			)
			(layer "F.SilkS")
		)
		(fp_line
			(start -0.67945 -0.305054)
			(end -0.12065 -0.305054)
			(stroke
				(width 0.1)
				(type default)
			)
			(layer "F.Fab")
		)
		(fp_line
			(start -0.67945 0.3048)
			(end -0.67945 -0.305054)
			(stroke
				(width 0.1)
				(type default)
			)
			(layer "F.Fab")
		)
		(fp_line
			(start -0.12065 -0.305054)
			(end -0.12065 -0.2794)
			(stroke
				(width 0.1)
				(type default)
			)
			(layer "F.Fab")
		)
		(fp_line
			(start -0.12065 -0.2794)
			(end 0.12065 -0.2794)
			(stroke
				(width 0.1)
				(type default)
			)
			(layer "F.Fab")
		)
		(fp_line
			(start -0.12065 0.2794)
			(end -0.12065 0.3048)
			(stroke
				(width 0.1)
				(type default)
			)
			(layer "F.Fab")
		)
		(fp_line
			(start -0.12065 0.3048)
			(end -0.67945 0.3048)
			(stroke
				(width 0.1)
				(type default)
			)
			(layer "F.Fab")
		)
		(fp_line
			(start 0.120396 0.2794)
			(end -0.12065 0.2794)
			(stroke
				(width 0.1)
				(type default)
			)
			(layer "F.Fab")
		)
		(fp_line
			(start 0.120396 0.3048)
			(end 0.120396 0.2794)
			(stroke
				(width 0.1)
				(type default)
			)
			(layer "F.Fab")
		)
		(fp_line
			(start 0.12065 -0.3048)
			(end 0.67945 -0.3048)
			(stroke
				(width 0.1)
				(type default)
			)
			(layer "F.Fab")
		)
		(fp_line
			(start 0.12065 -0.2794)
			(end 0.12065 -0.3048)
			(stroke
				(width 0.1)
				(type default)
			)
			(layer "F.Fab")
		)
		(fp_line
			(start 0.67945 -0.3048)
			(end 0.67945 0.3048)
			(stroke
				(width 0.1)
				(type default)
			)
			(layer "F.Fab")
		)
		(fp_line
			(start 0.67945 0.3048)
			(end 0.120396 0.3048)
			(stroke
				(width 0.1)
				(type default)
			)
			(layer "F.Fab")
		)
		(pad "1" smd circle
			(at -0.40005 0)
			(size 0 0)
			(layers "F.Cu" "F.Mask" "F.Paste")
			(net "RST_SMB_SWITCH_N")
		)
		(pad "2" smd circle
			(at 0.40005 0)
			(size 0 0)
			(layers "F.Cu" "F.Mask" "F.Paste")
			(net "PU_RST_SMB_PCIE0_N")
		)
	)
)
